(kicad_pcb
	(version 20260206)
	(generator "pcbnew")
	(generator_version "10.0")
	(general
		(thickness 1.6)
		(legacy_teardrops no)
	)
	(paper "A4")
	(title_block
		(title "01162023_DA0F0TEBIF0_F0T_Expander_BD_F_brd_V02_OCP.brd")
		(comment 1 "Grand Teton / footprints 458-463 of 9728")
	)
	(layers
		(0 "F.Cu" signal "TOP")
		(4 "In1.Cu" signal "GND")
		(6 "In2.Cu" signal "VCC")
		(8 "In3.Cu" signal "VCC1")
		(10 "In4.Cu" signal "GND1")
		(12 "In5.Cu" signal "IN1")
		(14 "In6.Cu" signal "GND2")
		(16 "In7.Cu" signal "IN2")
		(18 "In8.Cu" signal "GND3")
		(20 "In9.Cu" signal "IN3")
		(22 "In10.Cu" signal "GND4")
		(24 "In11.Cu" signal "IN4")
		(26 "In12.Cu" signal "GND5")
		(28 "In13.Cu" signal "IN5")
		(30 "In14.Cu" signal "GND6")
		(32 "In15.Cu" signal "IN6")
		(34 "In16.Cu" signal "GND7")
		(2 "B.Cu" signal "BOTTOM")
		(9 "F.Adhes" user "F.Adhesive")
		(11 "B.Adhes" user "B.Adhesive")
		(13 "F.Paste" user "Package Geometry/Pastemask Top")
		(15 "B.Paste" user "Package Geometry/Pastemask Bottom")
		(5 "F.SilkS" user "Ref Des/Silkscreen Top")
		(7 "B.SilkS" user "Ref Des/Silkscreen Bottom")
		(1 "F.Mask" user "Board Geometry/Soldermask Top")
		(3 "B.Mask" user "Board Geometry/Soldermask Bottom")
		(17 "Dwgs.User" user "User.Drawings")
		(19 "Cmts.User" user "User.Comments")
		(21 "Eco1.User" user "User.Eco1")
		(23 "Eco2.User" user "User.Eco2")
		(25 "Edge.Cuts" user "Board Geometry/Outline")
		(27 "Margin" user)
		(31 "F.CrtYd" user "Package Geometry/Place Bound Top")
		(29 "B.CrtYd" user "Package Geometry/Place Bound Bottom")
		(35 "F.Fab" user "Ref Des/Assembly Top")
		(33 "B.Fab" user "Ref Des/Assembly Bottom")
	)
	(footprint ""
		(layer "F.Cu")
		(at 351.26168 -284.834838 90)
		(property "Reference" "PC172"
			(at 0 0 90)
			(layer "F.SilkS")
			(hide yes)
			(effects
				(font
					(size 1.27 1.27)
				)
			)
		)
		(property "Value" ""
			(at 0 0 90)
			(layer "F.Fab")
			(effects
				(font
					(size 1.27 1.27)
				)
			)
		)
		(duplicate_pad_numbers_are_jumpers no)
		(fp_line
			(start 0.7874 -0.4064)
			(end 0.7874 0.4064)
			(stroke
				(width 0.1524)
				(type default)
			)
			(layer "F.SilkS")
		)
		(fp_line
			(start -0.7874 -0.4064)
			(end 0.7874 -0.4064)
			(stroke
				(width 0.1524)
				(type default)
			)
			(layer "F.SilkS")
		)
		(fp_line
			(start 0.7874 0.4064)
			(end -0.7874 0.4064)
			(stroke
				(width 0.1524)
				(type default)
			)
			(layer "F.SilkS")
		)
		(fp_line
			(start -0.7874 0.4064)
			(end -0.7874 -0.4064)
			(stroke
				(width 0.1524)
				(type default)
			)
			(layer "F.SilkS")
		)
		(fp_line
			(start -0.12065 -0.305054)
			(end -0.12065 -0.2794)
			(stroke
				(width 0.1)
				(type default)
			)
			(layer "F.Fab")
		)
		(fp_line
			(start -0.67945 -0.305054)
			(end -0.12065 -0.305054)
			(stroke
				(width 0.1)
				(type default)
			)
			(layer "F.Fab")
		)
		(fp_line
			(start 0.67945 -0.3048)
			(end 0.67945 0.3048)
			(stroke
				(width 0.1)
				(type default)
			)
			(layer "F.Fab")
		)
		(fp_line
			(start 0.12065 -0.3048)
			(end 0.67945 -0.3048)
			(stroke
				(width 0.1)
				(type default)
			)
			(layer "F.Fab")
		)
		(fp_line
			(start 0.12065 -0.2794)
			(end 0.12065 -0.3048)
			(stroke
				(width 0.1)
				(type default)
			)
			(layer "F.Fab")
		)
		(fp_line
			(start -0.12065 -0.2794)
			(end 0.12065 -0.2794)
			(stroke
				(width 0.1)
				(type default)
			)
			(layer "F.Fab")
		)
		(fp_line
			(start 0.120396 0.2794)
			(end -0.12065 0.2794)
			(stroke
				(width 0.1)
				(type default)
			)
			(layer "F.Fab")
		)
		(fp_line
			(start -0.12065 0.2794)
			(end -0.12065 0.3048)
			(stroke
				(width 0.1)
				(type default)
			)
			(layer "F.Fab")
		)
		(fp_line
			(start 0.67945 0.3048)
			(end 0.120396 0.3048)
			(stroke
				(width 0.1)
				(type default)
			)
			(layer "F.Fab")
		)
		(fp_line
			(start 0.120396 0.3048)
			(end 0.120396 0.2794)
			(stroke
				(width 0.1)
				(type default)
			)
			(layer "F.Fab")
		)
		(fp_line
			(start -0.12065 0.3048)
			(end -0.67945 0.3048)
			(stroke
				(width 0.1)
				(type default)
			)
			(layer "F.Fab")
		)
		(fp_line
			(start -0.67945 0.3048)
			(end -0.67945 -0.305054)
			(stroke
				(width 0.1)
				(type default)
			)
			(layer "F.Fab")
		)
		(pad "1" smd circle
			(at -0.40005 0 90)
			(size 0 0)
			(layers "F.Cu" "F.Mask" "F.Paste")
			(net "SW_P12V_P0V8_PEX3_FLT")
		)
		(pad "2" smd circle
			(at 0.40005 0 90)
			(size 0 0)
			(layers "F.Cu" "F.Mask" "F.Paste")
			(net "GND")
		)
	)
	(footprint ""
		(layer "F.Cu")
		(at 351.155 -234.061 -90)
		(property "Reference" "R3592"
			(at 0 0 270)
			(layer "F.SilkS")
			(hide yes)
			(effects
				(font
					(size 1.27 1.27)
				)
			)
		)
		(property "Value" ""
			(at 0 0 270)
			(layer "F.Fab")
			(effects
				(font
					(size 1.27 1.27)
				)
			)
		)
		(duplicate_pad_numbers_are_jumpers no)
		(fp_line
			(start -0.7874 0.4064)
			(end -0.7874 -0.4064)
			(stroke
				(width 0.1524)
				(type default)
			)
			(layer "F.SilkS")
		)
		(fp_line
			(start 0.7874 0.4064)
			(end -0.7874 0.4064)
			(stroke
				(width 0.1524)
				(type default)
			)
			(layer "F.SilkS")
		)
		(fp_line
			(start -0.7874 -0.4064)
			(end 0.7874 -0.4064)
			(stroke
				(width 0.1524)
				(type default)
			)
			(layer "F.SilkS")
		)
		(fp_line
			(start 0.7874 -0.4064)
			(end 0.7874 0.4064)
			(stroke
				(width 0.1524)
				(type default)
			)
			(layer "F.SilkS")
		)
		(fp_line
			(start -0.67945 0.3048)
			(end -0.67945 -0.305054)
			(stroke
				(width 0.1)
				(type default)
			)
			(layer "F.Fab")
		)
		(fp_line
			(start -0.12065 0.3048)
			(end -0.67945 0.3048)
			(stroke
				(width 0.1)
				(type default)
			)
			(layer "F.Fab")
		)
		(fp_line
			(start 0.120396 0.3048)
			(end 0.120396 0.2794)
			(stroke
				(width 0.1)
				(type default)
			)
			(layer "F.Fab")
		)
		(fp_line
			(start 0.67945 0.3048)
			(end 0.120396 0.3048)
			(stroke
				(width 0.1)
				(type default)
			)
			(layer "F.Fab")
		)
		(fp_line
			(start -0.12065 0.2794)
			(end -0.12065 0.3048)
			(stroke
				(width 0.1)
				(type default)
			)
			(layer "F.Fab")
		)
		(fp_line
			(start 0.120396 0.2794)
			(end -0.12065 0.2794)
			(stroke
				(width 0.1)
				(type default)
			)
			(layer "F.Fab")
		)
		(fp_line
			(start -0.12065 -0.2794)
			(end 0.12065 -0.2794)
			(stroke
				(width 0.1)
				(type default)
			)
			(layer "F.Fab")
		)
		(fp_line
			(start 0.12065 -0.2794)
			(end 0.12065 -0.3048)
			(stroke
				(width 0.1)
				(type default)
			)
			(layer "F.Fab")
		)
		(fp_line
			(start 0.12065 -0.3048)
			(end 0.67945 -0.3048)
			(stroke
				(width 0.1)
				(type default)
			)
			(layer "F.Fab")
		)
		(fp_line
			(start 0.67945 -0.3048)
			(end 0.67945 0.3048)
			(stroke
				(width 0.1)
				(type default)
			)
			(layer "F.Fab")
		)
		(fp_line
			(start -0.67945 -0.305054)
			(end -0.12065 -0.305054)
			(stroke
				(width 0.1)
				(type default)
			)
			(layer "F.Fab")
		)
		(fp_line
			(start -0.12065 -0.305054)
			(end -0.12065 -0.2794)
			(stroke
				(width 0.1)
				(type default)
			)
			(layer "F.Fab")
		)
		(pad "1" smd circle
			(at -0.40005 0 270)
			(size 0 0)
			(layers "F.Cu" "F.Mask" "F.Paste")
			(net "SSD7_PWR_EN_R")
		)
		(pad "2" smd circle
			(at 0.40005 0 270)
			(size 0 0)
			(layers "F.Cu" "F.Mask" "F.Paste")
			(net "SSD7_PWR_EN")
		)
	)
	(footprint ""
		(layer "F.Cu")
		(at 126.210314 -125.979428)
		(property "Reference" "R882"
			(at 0 0 0)
			(layer "F.SilkS")
			(hide yes)
			(effects
				(font
					(size 1.27 1.27)
				)
			)
		)
		(property "Value" ""
			(at 0 0 0)
			(layer "F.Fab")
			(effects
				(font
					(size 1.27 1.27)
				)
			)
		)
		(duplicate_pad_numbers_are_jumpers no)
		(fp_line
			(start -0.7874 -0.4064)
			(end 0.7874 -0.4064)
			(stroke
				(width 0.1524)
				(type default)
			)
			(layer "F.SilkS")
		)
		(fp_line
			(start -0.7874 0.4064)
			(end -0.7874 -0.4064)
			(stroke
				(width 0.1524)
				(type default)
			)
			(layer "F.SilkS")
		)
		(fp_line
			(start 0.7874 -0.4064)
			(end 0.7874 0.4064)
			(stroke
				(width 0.1524)
				(type default)
			)
			(layer "F.SilkS")
		)
		(fp_line
			(start 0.7874 0.4064)
			(end -0.7874 0.4064)
			(stroke
				(width 0.1524)
				(type default)
			)
			(layer "F.SilkS")
		)
		(fp_line
			(start -0.67945 -0.305054)
			(end -0.12065 -0.305054)
			(stroke
				(width 0.1)
				(type default)
			)
			(layer "F.Fab")
		)
		(fp_line
			(start -0.67945 0.3048)
			(end -0.67945 -0.305054)
			(stroke
				(width 0.1)
				(type default)
			)
			(layer "F.Fab")
		)
		(fp_line
			(start -0.12065 -0.305054)
			(end -0.12065 -0.2794)
			(stroke
				(width 0.1)
				(type default)
			)
			(layer "F.Fab")
		)
		(fp_line
			(start -0.12065 -0.2794)
			(end 0.12065 -0.2794)
			(stroke
				(width 0.1)
				(type default)
			)
			(layer "F.Fab")
		)
		(fp_line
			(start -0.12065 0.2794)
			(end -0.12065 0.3048)
			(stroke
				(width 0.1)
				(type default)
			)
			(layer "F.Fab")
		)
		(fp_line
			(start -0.12065 0.3048)
			(end -0.67945 0.3048)
			(stroke
				(width 0.1)
				(type default)
			)
			(layer "F.Fab")
		)
		(fp_line
			(start 0.120396 0.2794)
			(end -0.12065 0.2794)
			(stroke
				(width 0.1)
				(type default)
			)
			(layer "F.Fab")
		)
		(fp_line
			(start 0.120396 0.3048)
			(end 0.120396 0.2794)
			(stroke
				(width 0.1)
				(type default)
			)
			(layer "F.Fab")
		)
		(fp_line
			(start 0.12065 -0.3048)
			(end 0.67945 -0.3048)
			(stroke
				(width 0.1)
				(type default)
			)
			(layer "F.Fab")
		)
		(fp_line
			(start 0.12065 -0.2794)
			(end 0.12065 -0.3048)
			(stroke
				(width 0.1)
				(type default)
			)
			(layer "F.Fab")
		)
		(fp_line
			(start 0.67945 -0.3048)
			(end 0.67945 0.3048)
			(stroke
				(width 0.1)
				(type default)
			)
			(layer "F.Fab")
		)
		(fp_line
			(start 0.67945 0.3048)
			(end 0.120396 0.3048)
			(stroke
				(width 0.1)
				(type default)
			)
			(layer "F.Fab")
		)
		(pad "1" smd circle
			(at -0.40005 0)
			(size 0 0)
			(layers "F.Cu" "F.Mask" "F.Paste")
			(net "P3V3_NIC2")
		)
		(pad "2" smd circle
			(at 0.40005 0)
			(size 0 0)
			(layers "F.Cu" "F.Mask" "F.Paste")
			(net "PWRGD_P3V3_NIC2")
		)
	)
	(footprint ""
		(layer "F.Cu")
		(at 361.89031 -255.210564 180)
		(property "Reference" "R835"
			(at 0 0 180)
			(layer "F.SilkS")
			(hide yes)
			(effects
				(font
					(size 1.27 1.27)
				)
			)
		)
		(property "Value" ""
			(at 0 0 180)
			(layer "F.Fab")
			(effects
				(font
					(size 1.27 1.27)
				)
			)
		)
		(duplicate_pad_numbers_are_jumpers no)
		(fp_line
			(start 0.7874 0.4064)
			(end -0.7874 0.4064)
			(stroke
				(width 0.1524)
				(type default)
			)
			(layer "F.SilkS")
		)
		(fp_line
			(start 0.7874 -0.4064)
			(end 0.7874 0.4064)
			(stroke
				(width 0.1524)
				(type default)
			)
			(layer "F.SilkS")
		)
		(fp_line
			(start -0.7874 0.4064)
			(end -0.7874 -0.4064)
			(stroke
				(width 0.1524)
				(type default)
			)
			(layer "F.SilkS")
		)
		(fp_line
			(start -0.7874 -0.4064)
			(end 0.7874 -0.4064)
			(stroke
				(width 0.1524)
				(type default)
			)
			(layer "F.SilkS")
		)
		(fp_line
			(start 0.67945 0.3048)
			(end 0.120396 0.3048)
			(stroke
				(width 0.1)
				(type default)
			)
			(layer "F.Fab")
		)
		(fp_line
			(start 0.67945 -0.3048)
			(end 0.67945 0.3048)
			(stroke
				(width 0.1)
				(type default)
			)
			(layer "F.Fab")
		)
		(fp_line
			(start 0.12065 -0.2794)
			(end 0.12065 -0.3048)
			(stroke
				(width 0.1)
				(type default)
			)
			(layer "F.Fab")
		)
		(fp_line
			(start 0.12065 -0.3048)
			(end 0.67945 -0.3048)
			(stroke
				(width 0.1)
				(type default)
			)
			(layer "F.Fab")
		)
		(fp_line
			(start 0.120396 0.3048)
			(end 0.120396 0.2794)
			(stroke
				(width 0.1)
				(type default)
			)
			(layer "F.Fab")
		)
		(fp_line
			(start 0.120396 0.2794)
			(end -0.12065 0.2794)
			(stroke
				(width 0.1)
				(type default)
			)
			(layer "F.Fab")
		)
		(fp_line
			(start -0.12065 0.3048)
			(end -0.67945 0.3048)
			(stroke
				(width 0.1)
				(type default)
			)
			(layer "F.Fab")
		)
		(fp_line
			(start -0.12065 0.2794)
			(end -0.12065 0.3048)
			(stroke
				(width 0.1)
				(type default)
			)
			(layer "F.Fab")
		)
		(fp_line
			(start -0.12065 -0.2794)
			(end 0.12065 -0.2794)
			(stroke
				(width 0.1)
				(type default)
			)
			(layer "F.Fab")
		)
		(fp_line
			(start -0.12065 -0.305054)
			(end -0.12065 -0.2794)
			(stroke
				(width 0.1)
				(type default)
			)
			(layer "F.Fab")
		)
		(fp_line
			(start -0.67945 0.3048)
			(end -0.67945 -0.305054)
			(stroke
				(width 0.1)
				(type default)
			)
			(layer "F.Fab")
		)
		(fp_line
			(start -0.67945 -0.305054)
			(end -0.12065 -0.305054)
			(stroke
				(width 0.1)
				(type default)
			)
			(layer "F.Fab")
		)
		(pad "1" smd circle
			(at -0.40005 0 180)
			(size 0 0)
			(layers "F.Cu" "F.Mask" "F.Paste")
			(net "PWR_EN_PEX_R")
		)
		(pad "2" smd circle
			(at 0.40005 0 180)
			(size 0 0)
			(layers "F.Cu" "F.Mask" "F.Paste")
			(net "FM_P0V8_PEX2_EN_R")
		)
	)
	(footprint ""
		(layer "F.Cu")
		(at 329.454764 -202.265534)
		(property "Reference" "R4404"
			(at 0 0 0)
			(layer "F.SilkS")
			(hide yes)
			(effects
				(font
					(size 1.27 1.27)
				)
			)
		)
		(property "Value" ""
			(at 0 0 0)
			(layer "F.Fab")
			(effects
				(font
					(size 1.27 1.27)
				)
			)
		)
		(duplicate_pad_numbers_are_jumpers no)
		(fp_line
			(start -0.7874 -0.4064)
			(end 0.7874 -0.4064)
			(stroke
				(width 0.1524)
				(type default)
			)
			(layer "F.SilkS")
		)
		(fp_line
			(start -0.7874 0.4064)
			(end -0.7874 -0.4064)
			(stroke
				(width 0.1524)
				(type default)
			)
			(layer "F.SilkS")
		)
		(fp_line
			(start 0.7874 -0.4064)
			(end 0.7874 0.4064)
			(stroke
				(width 0.1524)
				(type default)
			)
			(layer "F.SilkS")
		)
		(fp_line
			(start 0.7874 0.4064)
			(end -0.7874 0.4064)
			(stroke
				(width 0.1524)
				(type default)
			)
			(layer "F.SilkS")
		)
		(fp_line
			(start -0.67945 -0.305054)
			(end -0.12065 -0.305054)
			(stroke
				(width 0.1)
				(type default)
			)
			(layer "F.Fab")
		)
		(fp_line
			(start -0.67945 0.3048)
			(end -0.67945 -0.305054)
			(stroke
				(width 0.1)
				(type default)
			)
			(layer "F.Fab")
		)
		(fp_line
			(start -0.12065 -0.305054)
			(end -0.12065 -0.2794)
			(stroke
				(width 0.1)
				(type default)
			)
			(layer "F.Fab")
		)
		(fp_line
			(start -0.12065 -0.2794)
			(end 0.12065 -0.2794)
			(stroke
				(width 0.1)
				(type default)
			)
			(layer "F.Fab")
		)
		(fp_line
			(start -0.12065 0.2794)
			(end -0.12065 0.3048)
			(stroke
				(width 0.1)
				(type default)
			)
			(layer "F.Fab")
		)
		(fp_line
			(start -0.12065 0.3048)
			(end -0.67945 0.3048)
			(stroke
				(width 0.1)
				(type default)
			)
			(layer "F.Fab")
		)
		(fp_line
			(start 0.120396 0.2794)
			(end -0.12065 0.2794)
			(stroke
				(width 0.1)
				(type default)
			)
			(layer "F.Fab")
		)
		(fp_line
			(start 0.120396 0.3048)
			(end 0.120396 0.2794)
			(stroke
				(width 0.1)
				(type default)
			)
			(layer "F.Fab")
		)
		(fp_line
			(start 0.12065 -0.3048)
			(end 0.67945 -0.3048)
			(stroke
				(width 0.1)
				(type default)
			)
			(layer "F.Fab")
		)
		(fp_line
			(start 0.12065 -0.2794)
			(end 0.12065 -0.3048)
			(stroke
				(width 0.1)
				(type default)
			)
			(layer "F.Fab")
		)
		(fp_line
			(start 0.67945 -0.3048)
			(end 0.67945 0.3048)
			(stroke
				(width 0.1)
				(type default)
			)
			(layer "F.Fab")
		)
		(fp_line
			(start 0.67945 0.3048)
			(end 0.120396 0.3048)
			(stroke
				(width 0.1)
				(type default)
			)
			(layer "F.Fab")
		)
		(pad "1" smd circle
			(at -0.40005 0)
			(size 0 0)
			(layers "F.Cu" "F.Mask" "F.Paste")
			(net "P3V3_AUX")
		)
		(pad "2" smd circle
			(at 0.40005 0)
			(size 0 0)
			(layers "F.Cu" "F.Mask" "F.Paste")
			(net "PU_CLK_25M_FPGA_EN")
		)
	)
	(footprint ""
		(layer "F.Cu")
		(at 210.658202 -224.24009 90)
		(property "Reference" "U302"
			(at 2.20726 -1.230376 90)
			(unlocked yes)
			(layer "F.SilkS")
			(effects
				(font
					(size 0.7874 0.5842)
					(thickness 0.1524)
				)
				(justify left)
			)
		)
		(property "Value" ""
			(at 0 0 90)
			(layer "F.Fab")
			(effects
				(font
					(size 1.27 1.27)
				)
			)
		)
		(duplicate_pad_numbers_are_jumpers no)
		(fp_line
			(start 1.684274 -1.074928)
			(end 1.684274 1.074928)
			(stroke
				(width 0.1524)
				(type default)
			)
			(layer "F.SilkS")
		)
		(fp_line
			(start 0.381 -1.074928)
			(end 1.684274 -1.074928)
			(stroke
				(width 0.1524)
				(type default)
			)
			(layer "F.SilkS")
		)
		(fp_line
			(start -0.381 -1.074928)
			(end 0 -0.625094)
			(stroke
				(width 0.1524)
				(type default)
			)
			(layer "F.SilkS")
		)
		(fp_line
			(start -1.684274 -1.074928)
			(end -0.381 -1.074928)
			(stroke
				(width 0.1524)
				(type default)
			)
			(layer "F.SilkS")
		)
		(fp_line
			(start 0 -0.625094)
			(end 0.381 -1.074928)
			(stroke
				(width 0.1524)
				(type default)
			)
			(layer "F.SilkS")
		)
		(fp_line
			(start 1.684274 1.074928)
			(end -1.684274 1.074928)
			(stroke
				(width 0.1524)
				(type default)
			)
			(layer "F.SilkS")
		)
		(fp_line
			(start -1.684274 1.074928)
			(end -1.684274 -1.074928)
			(stroke
				(width 0.1524)
				(type default)
			)
			(layer "F.SilkS")
		)
		(fp_poly
			(pts
				(xy -2.637282 -0.903986) (xy -2.637282 -0.395986) (xy -1.875282 -0.649986)
			)
			(stroke
				(width 0)
				(type default)
			)
			(fill yes)
			(layer "F.SilkS")
		)
		(fp_line
			(start 0.700024 -1.074928)
			(end -0.700024 -1.074928)
			(stroke
				(width 0.1)
				(type default)
			)
			(layer "F.Fab")
		)
		(fp_line
			(start -0.700024 -1.074928)
			(end -0.700024 1.074928)
			(stroke
				(width 0.1)
				(type default)
			)
			(layer "F.Fab")
		)
		(fp_line
			(start 0.700024 1.074928)
			(end 0.700024 -1.074928)
			(stroke
				(width 0.1)
				(type default)
			)
			(layer "F.Fab")
		)
		(fp_line
			(start -0.700024 1.074928)
			(end 0.700024 1.074928)
			(stroke
				(width 0.1)
				(type default)
			)
			(layer "F.Fab")
		)
		(fp_poly
			(pts
				(xy -2.637282 -0.903986) (xy -2.637282 -0.395986) (xy -1.875282 -0.649986)
			)
			(stroke
				(width 0)
				(type default)
			)
			(fill yes)
			(layer "F.Fab")
		)
		(pad "1" smd rect
			(at -1.100074 -0.649986)
			(size 0.4064 0.9144)
			(layers "F.Cu" "F.Mask" "F.Paste")
			(net "BUF_UART_MB_BIC_TX_EN")
		)
		(pad "2" smd rect
			(at -1.100074 0)
			(size 0.4064 0.9144)
			(layers "F.Cu" "F.Mask" "F.Paste")
			(net "UART_MB_BIC_R_TX")
		)
		(pad "3" smd rect
			(at -1.100074 0.649986)
			(size 0.4064 0.9144)
			(layers "F.Cu" "F.Mask" "F.Paste")
			(net "GND")
		)
		(pad "4" smd rect
			(at 1.100074 0.649986)
			(size 0.4064 0.9144)
			(layers "F.Cu" "F.Mask" "F.Paste")
			(net "UART_MB_BIC_TX_BUF")
		)
		(pad "5" smd rect
			(at 1.100074 -0.649986)
			(size 0.4064 0.9144)
			(layers "F.Cu" "F.Mask" "F.Paste")
			(net "P3V3_AUX")
		)
	)
)
